# SCM (Grand Teton) — schematic netlist excerpt (pin names and nets, part order shuffled) for the footprints in the layout excerpt that follows; sources: Cadence DE-HDL packaged netlist, KiCad conversion of 12092022_DA0F0TMDCD0_F0T_Management_Board_D_brd_V3_OCP.brd

R787  Q_RES  5.36K 1% CHIP  pkg 0402LF  page 15 : A = P5V_AUX ; B = P5V_SENSOR
R794  Q_RES  2K 1% CHIP  pkg 0402LF  page 15 : A = P1V8_SENSOR ; B = GND

(kicad_pcb
	(version 20260206)
	(generator "pcbnew")
	(generator_version "10.0")
	(general
		(thickness 1.6)
		(legacy_teardrops no)
	)
	(paper "A4")
	(title_block
		(title "12092022_DA0F0TMDCD0_F0T_Management_Board_D_brd_V3_OCP.brd")
		(comment 1 "Grand Teton / footprints 970-971 of 1440")
	)
	(layers
		(0 "F.Cu" signal "TOP")
		(4 "In1.Cu" signal "GND")
		(6 "In2.Cu" signal "IN1")
		(8 "In3.Cu" signal "GND1")
		(10 "In4.Cu" signal "IN2")
		(12 "In5.Cu" signal "VCC")
		(14 "In6.Cu" signal "VCC1")
		(16 "In7.Cu" signal "IN3")
		(18 "In8.Cu" signal "GND2")
		(20 "In9.Cu" signal "IN4")
		(22 "In10.Cu" signal "GND3")
		(2 "B.Cu" signal "BOTTOM")
		(9 "F.Adhes" user "F.Adhesive")
		(11 "B.Adhes" user "B.Adhesive")
		(13 "F.Paste" user "Package Geometry/Pastemask Top")
		(15 "B.Paste" user "Package Geometry/Pastemask Bottom")
		(5 "F.SilkS" user "Ref Des/Silkscreen Top")
		(7 "B.SilkS" user "Ref Des/Silkscreen Bottom")
		(1 "F.Mask" user "Board Geometry/Soldermask Top")
		(3 "B.Mask" user "Board Geometry/Soldermask Bottom")
		(17 "Dwgs.User" user "User.Drawings")
		(19 "Cmts.User" user "User.Comments")
		(21 "Eco1.User" user "User.Eco1")
		(23 "Eco2.User" user "User.Eco2")
		(25 "Edge.Cuts" user "Board Geometry/Outline")
		(27 "Margin" user)
		(31 "F.CrtYd" user "Package Geometry/Place Bound Top")
		(29 "B.CrtYd" user "Package Geometry/Place Bound Bottom")
		(35 "F.Fab" user "Ref Des/Assembly Top")
		(33 "B.Fab" user "Ref Des/Assembly Bottom")
	)
	(footprint ""
		(layer "B.Cu")
		(at 57.906666 -74.66584 180)
		(property "Reference" "R787"
			(at 0 0 0)
			(layer "B.SilkS")
			(hide yes)
			(effects
				(font
					(size 1.27 1.27)
				)
				(justify mirror)
			)
		)
		(property "Value" ""
			(at 0 0 0)
			(layer "B.Fab")
			(effects
				(font
					(size 1.27 1.27)
				)
				(justify mirror)
			)
		)
		(duplicate_pad_numbers_are_jumpers no)
		(fp_line
			(start 0.7874 0.4064)
			(end 0.7874 -0.4064)
			(stroke
				(width 0.1524)
				(type default)
			)
			(layer "B.SilkS")
		)
		(fp_line
			(start 0.7874 -0.4064)
			(end -0.7874 -0.4064)
			(stroke
				(width 0.1524)
				(type default)
			)
			(layer "B.SilkS")
		)
		(fp_line
			(start -0.7874 0.4064)
			(end 0.7874 0.4064)
			(stroke
				(width 0.1524)
				(type default)
			)
			(layer "B.SilkS")
		)
		(fp_line
			(start -0.7874 -0.4064)
			(end -0.7874 0.4064)
			(stroke
				(width 0.1524)
				(type default)
			)
			(layer "B.SilkS")
		)
		(fp_line
			(start 0.67945 0.3048)
			(end 0.67945 -0.305054)
			(stroke
				(width 0.1)
				(type default)
			)
			(layer "B.Fab")
		)
		(fp_line
			(start 0.67945 -0.305054)
			(end 0.12065 -0.305054)
			(stroke
				(width 0.1)
				(type default)
			)
			(layer "B.Fab")
		)
		(fp_line
			(start 0.12065 0.3048)
			(end 0.67945 0.3048)
			(stroke
				(width 0.1)
				(type default)
			)
			(layer "B.Fab")
		)
		(fp_line
			(start 0.12065 0.2794)
			(end 0.12065 0.3048)
			(stroke
				(width 0.1)
				(type default)
			)
			(layer "B.Fab")
		)
		(fp_line
			(start 0.12065 -0.2794)
			(end -0.12065 -0.2794)
			(stroke
				(width 0.1)
				(type default)
			)
			(layer "B.Fab")
		)
		(fp_line
			(start 0.12065 -0.305054)
			(end 0.12065 -0.2794)
			(stroke
				(width 0.1)
				(type default)
			)
			(layer "B.Fab")
		)
		(fp_line
			(start -0.120396 0.3048)
			(end -0.120396 0.2794)
			(stroke
				(width 0.1)
				(type default)
			)
			(layer "B.Fab")
		)
		(fp_line
			(start -0.120396 0.2794)
			(end 0.12065 0.2794)
			(stroke
				(width 0.1)
				(type default)
			)
			(layer "B.Fab")
		)
		(fp_line
			(start -0.12065 -0.2794)
			(end -0.12065 -0.3048)
			(stroke
				(width 0.1)
				(type default)
			)
			(layer "B.Fab")
		)
		(fp_line
			(start -0.12065 -0.3048)
			(end -0.67945 -0.3048)
			(stroke
				(width 0.1)
				(type default)
			)
			(layer "B.Fab")
		)
		(fp_line
			(start -0.67945 0.3048)
			(end -0.120396 0.3048)
			(stroke
				(width 0.1)
				(type default)
			)
			(layer "B.Fab")
		)
		(fp_line
			(start -0.67945 -0.3048)
			(end -0.67945 0.3048)
			(stroke
				(width 0.1)
				(type default)
			)
			(layer "B.Fab")
		)
		(pad "1" smd circle
			(at 0.40005 0)
			(size 0 0)
			(layers "B.Cu" "B.Mask" "B.Paste")
			(net "P5V_AUX")
		)
		(pad "2" smd circle
			(at -0.40005 0)
			(size 0 0)
			(layers "B.Cu" "B.Mask" "B.Paste")
			(net "P5V_SENSOR")
		)
	)
	(footprint ""
		(layer "B.Cu")
		(at 50.858674 -70.800722 180)
		(property "Reference" "R794"
			(at 0 0 0)
			(layer "B.SilkS")
			(hide yes)
			(effects
				(font
					(size 1.27 1.27)
				)
				(justify mirror)
			)
		)
		(property "Value" ""
			(at 0 0 0)
			(layer "B.Fab")
			(effects
				(font
					(size 1.27 1.27)
				)
				(justify mirror)
			)
		)
		(duplicate_pad_numbers_are_jumpers no)
		(fp_line
			(start 0.7874 0.4064)
			(end 0.7874 -0.4064)
			(stroke
				(width 0.1524)
				(type default)
			)
			(layer "B.SilkS")
		)
		(fp_line
			(start 0.7874 -0.4064)
			(end -0.7874 -0.4064)
			(stroke
				(width 0.1524)
				(type default)
			)
			(layer "B.SilkS")
		)
		(fp_line
			(start -0.7874 0.4064)
			(end 0.7874 0.4064)
			(stroke
				(width 0.1524)
				(type default)
			)
			(layer "B.SilkS")
		)
		(fp_line
			(start -0.7874 -0.4064)
			(end -0.7874 0.4064)
			(stroke
				(width 0.1524)
				(type default)
			)
			(layer "B.SilkS")
		)
		(fp_line
			(start 0.67945 0.3048)
			(end 0.67945 -0.305054)
			(stroke
				(width 0.1)
				(type default)
			)
			(layer "B.Fab")
		)
		(fp_line
			(start 0.67945 -0.305054)
			(end 0.12065 -0.305054)
			(stroke
				(width 0.1)
				(type default)
			)
			(layer "B.Fab")
		)
		(fp_line
			(start 0.12065 0.3048)
			(end 0.67945 0.3048)
			(stroke
				(width 0.1)
				(type default)
			)
			(layer "B.Fab")
		)
		(fp_line
			(start 0.12065 0.2794)
			(end 0.12065 0.3048)
			(stroke
				(width 0.1)
				(type default)
			)
			(layer "B.Fab")
		)
		(fp_line
			(start 0.12065 -0.2794)
			(end -0.12065 -0.2794)
			(stroke
				(width 0.1)
				(type default)
			)
			(layer "B.Fab")
		)
		(fp_line
			(start 0.12065 -0.305054)
			(end 0.12065 -0.2794)
			(stroke
				(width 0.1)
				(type default)
			)
			(layer "B.Fab")
		)
		(fp_line
			(start -0.120396 0.3048)
			(end -0.120396 0.2794)
			(stroke
				(width 0.1)
				(type default)
			)
			(layer "B.Fab")
		)
		(fp_line
			(start -0.120396 0.2794)
			(end 0.12065 0.2794)
			(stroke
				(width 0.1)
				(type default)
			)
			(layer "B.Fab")
		)
		(fp_line
			(start -0.12065 -0.2794)
			(end -0.12065 -0.3048)
			(stroke
				(width 0.1)
				(type default)
			)
			(layer "B.Fab")
		)
		(fp_line
			(start -0.12065 -0.3048)
			(end -0.67945 -0.3048)
			(stroke
				(width 0.1)
				(type default)
			)
			(layer "B.Fab")
		)
		(fp_line
			(start -0.67945 0.3048)
			(end -0.120396 0.3048)
			(stroke
				(width 0.1)
				(type default)
			)
			(layer "B.Fab")
		)
		(fp_line
			(start -0.67945 -0.3048)
			(end -0.67945 0.3048)
			(stroke
				(width 0.1)
				(type default)
			)
			(layer "B.Fab")
		)
		(pad "1" smd circle
			(at 0.40005 0)
			(size 0 0)
			(layers "B.Cu" "B.Mask" "B.Paste")
			(net "P1V8_SENSOR")
		)
		(pad "2" smd circle
			(at -0.40005 0)
			(size 0 0)
			(layers "B.Cu" "B.Mask" "B.Paste")
			(net "GND")
		)
	)
)
